# T6G (Grand Teton) — schematic netlist excerpt (pin names and nets, part order shuffled) for the footprints in the layout excerpt that follows; sources: Cadence DE-HDL packaged netlist, KiCad conversion of 04192023_DAF0TMB3IC0_F0TG_MB_C_brd_V02_OCP.brd

R728  Q_RES  4.7K 5% EMPTY  pkg 0201LF  page 320 : A = MODE_RT_CPU1_P0 ; B = GND
R1355  Q_RES  0 5% CHIP  pkg 0402LF  page 357 : A = INA230_6_A0 ; B = SMB_INA230_6_3V3AUX_SDA_R1
R354  Q_RES  10.5K 1% CHIP  pkg 0402LF  page 267 : A = P3V3_AUX ; B = P12V_HSC_T_CRIT_R_N

(kicad_pcb
	(version 20260206)
	(generator "pcbnew")
	(generator_version "10.0")
	(general
		(thickness 1.6)
		(legacy_teardrops no)
	)
	(paper "A4")
	(title_block
		(title "04192023_DAF0TMB3IC0_F0TG_MB_C_brd_V02_OCP.brd")
		(comment 1 "Grand Teton / footprints 985-987 of 8354")
	)
	(layers
		(0 "F.Cu" signal "TOP")
		(4 "In1.Cu" signal "GND")
		(6 "In2.Cu" signal "IN1")
		(8 "In3.Cu" signal "GND1")
		(10 "In4.Cu" signal "IN2")
		(12 "In5.Cu" signal "GND2")
		(14 "In6.Cu" signal "IN3")
		(16 "In7.Cu" signal "GND3")
		(18 "In8.Cu" signal "VCC")
		(20 "In9.Cu" signal "VCC1")
		(22 "In10.Cu" signal "GND4")
		(24 "In11.Cu" signal "IN4")
		(26 "In12.Cu" signal "GND5")
		(28 "In13.Cu" signal "IN5")
		(30 "In14.Cu" signal "GND6")
		(32 "In15.Cu" signal "IN6")
		(34 "In16.Cu" signal "GND7")
		(2 "B.Cu" signal "BOTTOM")
		(9 "F.Adhes" user "F.Adhesive")
		(11 "B.Adhes" user "B.Adhesive")
		(13 "F.Paste" user "Package Geometry/Pastemask Top")
		(15 "B.Paste" user "Package Geometry/Pastemask Bottom")
		(5 "F.SilkS" user "Ref Des/Silkscreen Top")
		(7 "B.SilkS" user "Ref Des/Silkscreen Bottom")
		(1 "F.Mask" user "Board Geometry/Soldermask Top")
		(3 "B.Mask" user "Board Geometry/Soldermask Bottom")
		(17 "Dwgs.User" user "User.Drawings")
		(19 "Cmts.User" user "User.Comments")
		(21 "Eco1.User" user "User.Eco1")
		(23 "Eco2.User" user "User.Eco2")
		(25 "Edge.Cuts" user "Board Geometry/Outline")
		(27 "Margin" user)
		(31 "F.CrtYd" user "Package Geometry/Place Bound Top")
		(29 "B.CrtYd" user "Package Geometry/Place Bound Bottom")
		(35 "F.Fab" user "Ref Des/Assembly Top")
		(33 "B.Fab" user "Ref Des/Assembly Bottom")
	)
	(footprint ""
		(layer "F.Cu")
		(at 283.216858 -405.066754 -90)
		(property "Reference" "R354"
			(at 0 0 270)
			(layer "F.SilkS")
			(hide yes)
			(effects
				(font
					(size 1.27 1.27)
				)
			)
		)
		(property "Value" ""
			(at 0 0 270)
			(layer "F.Fab")
			(effects
				(font
					(size 1.27 1.27)
				)
			)
		)
		(duplicate_pad_numbers_are_jumpers no)
		(fp_line
			(start -0.7874 0.4064)
			(end -0.7874 -0.4064)
			(stroke
				(width 0.1524)
				(type default)
			)
			(layer "F.SilkS")
		)
		(fp_line
			(start 0.7874 0.4064)
			(end -0.7874 0.4064)
			(stroke
				(width 0.1524)
				(type default)
			)
			(layer "F.SilkS")
		)
		(fp_line
			(start -0.7874 -0.4064)
			(end 0.7874 -0.4064)
			(stroke
				(width 0.1524)
				(type default)
			)
			(layer "F.SilkS")
		)
		(fp_line
			(start 0.7874 -0.4064)
			(end 0.7874 0.4064)
			(stroke
				(width 0.1524)
				(type default)
			)
			(layer "F.SilkS")
		)
		(fp_line
			(start -0.67945 0.3048)
			(end -0.67945 -0.305054)
			(stroke
				(width 0.1)
				(type default)
			)
			(layer "F.Fab")
		)
		(fp_line
			(start -0.12065 0.3048)
			(end -0.67945 0.3048)
			(stroke
				(width 0.1)
				(type default)
			)
			(layer "F.Fab")
		)
		(fp_line
			(start 0.120396 0.3048)
			(end 0.120396 0.2794)
			(stroke
				(width 0.1)
				(type default)
			)
			(layer "F.Fab")
		)
		(fp_line
			(start 0.67945 0.3048)
			(end 0.120396 0.3048)
			(stroke
				(width 0.1)
				(type default)
			)
			(layer "F.Fab")
		)
		(fp_line
			(start -0.12065 0.2794)
			(end -0.12065 0.3048)
			(stroke
				(width 0.1)
				(type default)
			)
			(layer "F.Fab")
		)
		(fp_line
			(start 0.120396 0.2794)
			(end -0.12065 0.2794)
			(stroke
				(width 0.1)
				(type default)
			)
			(layer "F.Fab")
		)
		(fp_line
			(start -0.12065 -0.2794)
			(end 0.12065 -0.2794)
			(stroke
				(width 0.1)
				(type default)
			)
			(layer "F.Fab")
		)
		(fp_line
			(start 0.12065 -0.2794)
			(end 0.12065 -0.3048)
			(stroke
				(width 0.1)
				(type default)
			)
			(layer "F.Fab")
		)
		(fp_line
			(start 0.12065 -0.3048)
			(end 0.67945 -0.3048)
			(stroke
				(width 0.1)
				(type default)
			)
			(layer "F.Fab")
		)
		(fp_line
			(start 0.67945 -0.3048)
			(end 0.67945 0.3048)
			(stroke
				(width 0.1)
				(type default)
			)
			(layer "F.Fab")
		)
		(fp_line
			(start -0.67945 -0.305054)
			(end -0.12065 -0.305054)
			(stroke
				(width 0.1)
				(type default)
			)
			(layer "F.Fab")
		)
		(fp_line
			(start -0.12065 -0.305054)
			(end -0.12065 -0.2794)
			(stroke
				(width 0.1)
				(type default)
			)
			(layer "F.Fab")
		)
		(pad "1" smd circle
			(at -0.40005 0 270)
			(size 0 0)
			(layers "F.Cu" "F.Mask" "F.Paste")
			(net "P3V3_AUX")
		)
		(pad "2" smd circle
			(at 0.40005 0 270)
			(size 0 0)
			(layers "F.Cu" "F.Mask" "F.Paste")
			(net "P12V_HSC_T_CRIT_R_N")
		)
	)
	(footprint ""
		(layer "F.Cu")
		(at 41.5544 -390.652)
		(property "Reference" "R728"
			(at 0 0 0)
			(layer "F.SilkS")
			(hide yes)
			(effects
				(font
					(size 1.27 1.27)
				)
			)
		)
		(property "Value" ""
			(at 0 0 0)
			(layer "F.Fab")
			(effects
				(font
					(size 1.27 1.27)
				)
			)
		)
		(duplicate_pad_numbers_are_jumpers no)
		(fp_line
			(start -0.32512 -0.175006)
			(end 0.32512 -0.175006)
			(stroke
				(width 0.1)
				(type default)
			)
			(layer "F.Fab")
		)
		(fp_line
			(start -0.32512 0.175006)
			(end -0.32512 -0.175006)
			(stroke
				(width 0.1)
				(type default)
			)
			(layer "F.Fab")
		)
		(fp_line
			(start 0.32512 -0.175006)
			(end 0.32512 0.175006)
			(stroke
				(width 0.1)
				(type default)
			)
			(layer "F.Fab")
		)
		(fp_line
			(start 0.32512 0.175006)
			(end -0.32512 0.175006)
			(stroke
				(width 0.1)
				(type default)
			)
			(layer "F.Fab")
		)
		(pad "1" smd rect
			(at -0.2667 0)
			(size 0.3048 0.381)
			(layers "F.Cu" "F.Mask" "F.Paste")
			(net "MODE_RT_CPU1_P0")
		)
		(pad "2" smd rect
			(at 0.2667 0 180)
			(size 0.3048 0.381)
			(layers "F.Cu" "F.Mask" "F.Paste")
			(net "GND")
		)
	)
	(footprint ""
		(layer "F.Cu")
		(at 391.291318 -75.391264 180)
		(property "Reference" "R1355"
			(at 0 0 180)
			(layer "F.SilkS")
			(hide yes)
			(effects
				(font
					(size 1.27 1.27)
				)
			)
		)
		(property "Value" ""
			(at 0 0 180)
			(layer "F.Fab")
			(effects
				(font
					(size 1.27 1.27)
				)
			)
		)
		(duplicate_pad_numbers_are_jumpers no)
		(fp_line
			(start 0.7874 0.4064)
			(end -0.7874 0.4064)
			(stroke
				(width 0.1524)
				(type default)
			)
			(layer "F.SilkS")
		)
		(fp_line
			(start 0.7874 -0.4064)
			(end 0.7874 0.4064)
			(stroke
				(width 0.1524)
				(type default)
			)
			(layer "F.SilkS")
		)
		(fp_line
			(start -0.7874 0.4064)
			(end -0.7874 -0.4064)
			(stroke
				(width 0.1524)
				(type default)
			)
			(layer "F.SilkS")
		)
		(fp_line
			(start -0.7874 -0.4064)
			(end 0.7874 -0.4064)
			(stroke
				(width 0.1524)
				(type default)
			)
			(layer "F.SilkS")
		)
		(fp_line
			(start 0.67945 0.3048)
			(end 0.120396 0.3048)
			(stroke
				(width 0.1)
				(type default)
			)
			(layer "F.Fab")
		)
		(fp_line
			(start 0.67945 -0.3048)
			(end 0.67945 0.3048)
			(stroke
				(width 0.1)
				(type default)
			)
			(layer "F.Fab")
		)
		(fp_line
			(start 0.12065 -0.2794)
			(end 0.12065 -0.3048)
			(stroke
				(width 0.1)
				(type default)
			)
			(layer "F.Fab")
		)
		(fp_line
			(start 0.12065 -0.3048)
			(end 0.67945 -0.3048)
			(stroke
				(width 0.1)
				(type default)
			)
			(layer "F.Fab")
		)
		(fp_line
			(start 0.120396 0.3048)
			(end 0.120396 0.2794)
			(stroke
				(width 0.1)
				(type default)
			)
			(layer "F.Fab")
		)
		(fp_line
			(start 0.120396 0.2794)
			(end -0.12065 0.2794)
			(stroke
				(width 0.1)
				(type default)
			)
			(layer "F.Fab")
		)
		(fp_line
			(start -0.12065 0.3048)
			(end -0.67945 0.3048)
			(stroke
				(width 0.1)
				(type default)
			)
			(layer "F.Fab")
		)
		(fp_line
			(start -0.12065 0.2794)
			(end -0.12065 0.3048)
			(stroke
				(width 0.1)
				(type default)
			)
			(layer "F.Fab")
		)
		(fp_line
			(start -0.12065 -0.2794)
			(end 0.12065 -0.2794)
			(stroke
				(width 0.1)
				(type default)
			)
			(layer "F.Fab")
		)
		(fp_line
			(start -0.12065 -0.305054)
			(end -0.12065 -0.2794)
			(stroke
				(width 0.1)
				(type default)
			)
			(layer "F.Fab")
		)
		(fp_line
			(start -0.67945 0.3048)
			(end -0.67945 -0.305054)
			(stroke
				(width 0.1)
				(type default)
			)
			(layer "F.Fab")
		)
		(fp_line
			(start -0.67945 -0.305054)
			(end -0.12065 -0.305054)
			(stroke
				(width 0.1)
				(type default)
			)
			(layer "F.Fab")
		)
		(pad "1" smd circle
			(at -0.40005 0 180)
			(size 0 0)
			(layers "F.Cu" "F.Mask" "F.Paste")
			(net "INA230_6_A0")
		)
		(pad "2" smd circle
			(at 0.40005 0 180)
			(size 0 0)
			(layers "F.Cu" "F.Mask" "F.Paste")
			(net "SMB_INA230_6_3V3AUX_SDA_R1")
		)
	)
)
